# BASEBOARD_FAB2 (Tioga Pass) — schematic netlist excerpt (pin names and nets, part order shuffled) for the footprints in the layout excerpt that follows; sources: Cadence DE-HDL packaged netlist, KiCad conversion of Wiwynn_Tioga_Pass_MB.brd

J1B1  SCONN288_H44441004  SCONN  pkg PIP  page 83
  \12v\(1)  = P12V_NVDIMM_KLM
  VSS(93)  = GND
  DQ(4)  = M_K_DQ<5>
  VSS(92)  = GND
  DQ(0)  = M_K_DQ<1>
  VSS(91)  = GND
  DQS9P  = M_K_DQS_DP<9>
  DQS9N  = M_K_DQS_DN<9>
  VSS(90)  = GND
  DQ(6)  = M_K_DQ<7>
  VSS(89)  = GND
  DQ(2)  = M_K_DQ<3>
  VSS(88)  = GND
  DQ(12)  = M_K_DQ<13>
  VSS(87)  = GND
  DQ(8)  = M_K_DQ<9>
  VSS(86)  = GND
  DQS10P  = M_K_DQS_DP<10>
  DQS10N  = M_K_DQS_DN<10>
  VSS(85)  = GND
  DQ(14)  = M_K_DQ<15>
  VSS(84)  = GND
  DQ(10)  = M_K_DQ<11>
  VSS(83)  = GND
  DQ(20)  = M_K_DQ<21>
  VSS(82)  = GND
  DQ(16)  = M_K_DQ<17>
  VSS(81)  = GND
  DQS11P  = M_K_DQS_DP<11>
  DQS11N  = M_K_DQS_DN<11>
  VSS(80)  = GND
  DQ(22)  = M_K_DQ<23>
  VSS(79)  = GND
  DQ(18)  = M_K_DQ<19>
  VSS(78)  = GND
  DQ(28)  = M_K_DQ<29>
  VSS(77)  = GND
  DQ(24)  = M_K_DQ<25>
  VSS(76)  = GND
  DQS12P  = M_K_DQS_DP<12>
  DQS12N  = M_K_DQS_DN<12>
  VSS(75)  = GND
  DQ(30)  = M_K_DQ<31>
  VSS(74)  = GND
  DQ(26)  = M_K_DQ<27>
  VSS(73)  = GND
  CB(4)  = M_K_ECC<5>
  VSS(72)  = GND
  CB(0)  = M_K_ECC<1>
  VSS(71)  = GND
  DQS17P  = M_K_DQS_DP<17>
  DQS17N  = M_K_DQS_DN<17>
  VSS(70)  = GND
  CB(6)  = M_K_ECC<7>
  VSS(69)  = GND
  CB(2)  = M_K_ECC<3>
  VSS(68)  = GND
  RESET_N  = M_KLM_RST_N
  VDD(25)  = PVDDQ_KLM
  CKE(0)  = M_K_CKE<0>
  VDD(24)  = PVDDQ_KLM
  ACT_N  = M_K_ACT_N
  BG(0)  = M_K_BG<0>
  VDD(23)  = PVDDQ_KLM
  A12  = M_K_MA<12>
  A9  = M_K_MA<9>
  VDD(22)  = PVDDQ_KLM
  A8  = M_K_MA<8>
  A6  = M_K_MA<6>
  VDD(21)  = PVDDQ_KLM
  A3  = M_K_MA<3>
  A1  = M_K_MA<1>
  VDD(20)  = PVDDQ_KLM
  CK0P  = M_K_CLK_DP<0>
  CK0N  = M_K_CLK_DN<0>
  VDD(19)  = PVDDQ_KLM
  VTT(1)  = PVTT_KLM
  EVENT_N  = FM_DIMM_EVENT_COD_N
  A0  = M_K_MA<0>
  VDD(18)  = PVDDQ_KLM
  BA(0)  = M_K_BA<0>
  A16_RAS_N  = M_K_MA<16>
  VDD(17)  = PVDDQ_KLM
  S0_N  = M_K_CS_N<0>
  VDD(16)  = PVDDQ_KLM
  A15_CAS_N  = M_K_MA<15>
  ODT(0)  = M_K_ODT<0>
  VDD(15)  = PVDDQ_KLM
  S1_N  = M_K_CS_N<1>
  VDD(14)  = PVDDQ_KLM
  ODT(1)  = M_K_ODT<1>
  VDD(13)  = PVDDQ_KLM
  S2_N_C(0)  = M_K_CS_N<2>
  VSS(67)  = GND
  DQ(36)  = M_K_DQ<37>
  VSS(66)  = GND
  DQ(32)  = M_K_DQ<33>
  VSS(65)  = GND
  DQS13P  = M_K_DQS_DP<13>
  DQS13N  = M_K_DQS_DN<13>
  VSS(64)  = GND
  DQ(38)  = M_K_DQ<39>
  VSS(63)  = GND
  DQ(34)  = M_K_DQ<35>
  VSS(62)  = GND
  DQ(44)  = M_K_DQ<45>
  VSS(61)  = GND
  DQ(40)  = M_K_DQ<41>
  VSS(60)  = GND
  DQS14P  = M_K_DQS_DP<14>
  DQS14N  = M_K_DQS_DN<14>
  VSS(59)  = GND
  DQ(46)  = M_K_DQ<47>
  VSS(58)  = GND
  DQ(42)  = M_K_DQ<43>
  VSS(57)  = GND
  DQ(52)  = M_K_DQ<53>
  VSS(56)  = GND
  DQ(48)  = M_K_DQ<49>
  VSS(55)  = GND
  DQS15P  = M_K_DQS_DP<15>
  DQS15N  = M_K_DQS_DN<15>
  VSS(54)  = GND
  DQ(54)  = M_K_DQ<55>
  VSS(53)  = GND
  DQ(50)  = M_K_DQ<51>
  VSS(52)  = GND
  DQ(60)  = M_K_DQ<61>
  VSS(51)  = GND
  DQ(56)  = M_K_DQ<57>
  VSS(50)  = GND
  DQS16P  = M_K_DQS_DP<16>
  DQS16N  = M_K_DQS_DN<16>
  VSS(49)  = GND
  DQ(62)  = M_K_DQ<63>
  VSS(48)  = GND
  DQ(58)  = M_K_DQ<59>
  VSS(47)  = GND
  SA(0)  = GND
  SA(1)  = GND
  SCL  = SMB_DDR_KLM_VPP_SCL
  VPP(4)  = PVPP_KLM
  VPP(3)  = PVPP_KLM
  RFU(2)  = TP_CH_K_DIMM_K0_RFU_2
  \12v\(0)  = P12V_NVDIMM_KLM
  VREFCA  = M_K_VREF
  VSS(46)  = GND
  DQ(5)  = M_K_DQ<4>
  VSS(45)  = GND
  DQ(1)  = M_K_DQ<0>
  VSS(44)  = GND
  DQS0N  = M_K_DQS_DN<0>
  DQS0P  = M_K_DQS_DP<0>
  VSS(43)  = GND
  DQ(7)  = M_K_DQ<6>
  VSS(42)  = GND
  DQ(3)  = M_K_DQ<2>
  VSS(41)  = GND
  DQ(13)  = M_K_DQ<12>
  VSS(40)  = GND
  DQ(9)  = M_K_DQ<8>
  VSS(39)  = GND
  DQS1N  = M_K_DQS_DN<1>
  DQS1P  = M_K_DQS_DP<1>
  VSS(38)  = GND
  DQ(15)  = M_K_DQ<14>
  VSS(37)  = GND
  DQ(11)  = M_K_DQ<10>
  VSS(36)  = GND
  DQ(21)  = M_K_DQ<20>
  VSS(35)  = GND
  DQ(17)  = M_K_DQ<16>
  VSS(34)  = GND
  DQS2N  = M_K_DQS_DN<2>
  DQS2P  = M_K_DQS_DP<2>
  VSS(33)  = GND
  DQ(23)  = M_K_DQ<22>
  VSS(32)  = GND
  DQ(19)  = M_K_DQ<18>
  VSS(31)  = GND
  DQ(29)  = M_K_DQ<28>
  VSS(30)  = GND
  DQ(25)  = M_K_DQ<24>
  VSS(29)  = GND
  DQS3N  = M_K_DQS_DN<3>
  DQS3P  = M_K_DQS_DP<3>
  VSS(28)  = GND
  DQ(31)  = M_K_DQ<30>
  VSS(27)  = GND
  DQ(27)  = M_K_DQ<26>
  VSS(26)  = GND
  CB(5)  = M_K_ECC<4>
  VSS(25)  = GND
  CB(1)  = M_K_ECC<0>
  VSS(24)  = GND
  DQS8N  = M_K_DQS_DN<8>
  DQS8P  = M_K_DQS_DP<8>
  VSS(23)  = GND
  CB(7)  = M_K_ECC<6>
  VSS(22)  = GND
  CB(3)  = M_K_ECC<2>
  VSS(21)  = GND
  CKE(1)  = M_K_CKE<1>
  VDD(12)  = PVDDQ_KLM
  RFU(0)  = TP_CH_K_DIMM_K0_RFU_0
  VDD(11)  = PVDDQ_KLM
  BG(1)  = M_K_BG<1>
  ALERT_N  = M_K_ALERT_N
  VDD(10)  = PVDDQ_KLM
  A11  = M_K_MA<11>
  A7  = M_K_MA<7>
  VDD(9)  = PVDDQ_KLM
  A5  = M_K_MA<5>
  A4  = M_K_MA<4>
  VDD(8)  = PVDDQ_KLM
  A2  = M_K_MA<2>
  VDD(7)  = PVDDQ_KLM
  CK1P  = M_K_CLK_DP<1>
  CK1N  = M_K_CLK_DN<1>
  VDD(6)  = PVDDQ_KLM
  VTT(0)  = PVTT_KLM
  PAR  = M_K_PAR
  VDD(5)  = PVDDQ_KLM
  BA(1)  = M_K_BA<1>
  A10  = M_K_MA<10>
  VDD(4)  = PVDDQ_KLM
  RFU(1)  = TP_CH_K_DIMM_K0_RFU_1
  A14_WE_N  = M_K_MA<14>
  VDD(3)  = PVDDQ_KLM
  SAVE_N_NC  = FM_ADR_COMPLETE_KLM_N
  VDD(2)  = PVDDQ_KLM
  A13  = M_K_MA<13>
  VDD(1)  = PVDDQ_KLM
  A17  = M_K_MA<17>
  C(2)  = M_K_C<2>
  VDD(0)  = PVDDQ_KLM
  S3_N_C(1)  = M_K_CS_N<3>
  SA(2)  = GND
  VSS(20)  = GND
  DQ(37)  = M_K_DQ<36>
  VSS(19)  = GND
  DQ(33)  = M_K_DQ<32>
  VSS(18)  = GND
  DQS4N  = M_K_DQS_DN<4>
  DQS4P  = M_K_DQS_DP<4>
  VSS(17)  = GND
  DQ(39)  = M_K_DQ<38>
  VSS(16)  = GND
  DQ(35)  = M_K_DQ<34>
  VSS(15)  = GND
  DQ(45)  = M_K_DQ<44>
  VSS(14)  = GND
  DQ(41)  = M_K_DQ<40>
  VSS(13)  = GND
  DQS5N  = M_K_DQS_DN<5>
  DQS5P  = M_K_DQS_DP<5>
  VSS(12)  = GND
  DQ(47)  = M_K_DQ<46>
  VSS(11)  = GND
  DQ(43)  = M_K_DQ<42>
  VSS(10)  = GND
  DQ(53)  = M_K_DQ<52>
  VSS(9)  = GND
  DQ(49)  = M_K_DQ<48>
  VSS(8)  = GND
  DQS6N  = M_K_DQS_DN<6>
  DQS6P  = M_K_DQS_DP<6>
  VSS(7)  = GND
  DQ(55)  = M_K_DQ<54>
  VSS(6)  = GND
  DQ(51)  = M_K_DQ<50>
  VSS(5)  = GND
  DQ(61)  = M_K_DQ<60>
  VSS(4)  = GND
  DQ(57)  = M_K_DQ<56>
  VSS(3)  = GND
  DQS7N  = M_K_DQS_DN<7>
  DQS7P  = M_K_DQS_DP<7>
  VSS(2)  = GND
  DQ(63)  = M_K_DQ<62>
  VSS(1)  = GND
  DQ(59)  = M_K_DQ<58>
  VSS(0)  = GND
  VDDSPD  = PVPP_KLM
  SDA  = SMB_DDR_KLM_VPP_SDA
  VPP(1)  = PVPP_KLM
  VPP(0)  = PVPP_KLM
  VPP(2)  = PVPP_KLM

(kicad_pcb
	(version 20260206)
	(generator "pcbnew")
	(generator_version "10.0")
	(general
		(thickness 1.6)
		(legacy_teardrops no)
	)
	(paper "A4")
	(title_block
		(title "Wiwynn_Tioga_Pass_MB.brd")
		(comment 1 "Tioga Pass / footprint 320 of 4770 (J1B1), pads 153-202 of 291")
	)
	(layers
		(0 "F.Cu" signal "TOP")
		(4 "In1.Cu" signal "L2GND")
		(6 "In2.Cu" signal "L3")
		(8 "In3.Cu" signal "L4GND")
		(10 "In4.Cu" signal "L5")
		(12 "In5.Cu" signal "L6GND")
		(14 "In6.Cu" signal "L7VCC")
		(16 "In7.Cu" signal "L8VCC")
		(18 "In8.Cu" signal "L9GND")
		(20 "In9.Cu" signal "L10")
		(22 "In10.Cu" signal "L11GND")
		(24 "In11.Cu" signal "L12")
		(26 "In12.Cu" signal "L13GND")
		(2 "B.Cu" signal "BOTTOM")
		(9 "F.Adhes" user "F.Adhesive")
		(11 "B.Adhes" user "B.Adhesive")
		(13 "F.Paste" user "Package Geometry/Pastemask Top")
		(15 "B.Paste" user "Package Geometry/Pastemask Bottom")
		(5 "F.SilkS" user "Ref Des/Silkscreen Top")
		(7 "B.SilkS" user "Ref Des/Silkscreen Bottom")
		(1 "F.Mask" user "Board Geometry/Soldermask Top")
		(3 "B.Mask" user "Board Geometry/Soldermask Bottom")
		(17 "Dwgs.User" user "User.Drawings")
		(19 "Cmts.User" user "User.Comments")
		(21 "Eco1.User" user "User.Eco1")
		(23 "Eco2.User" user "User.Eco2")
		(25 "Edge.Cuts" user "Board Geometry/Outline")
		(27 "Margin" user)
		(31 "F.CrtYd" user "Package Geometry/Place Bound Top")
		(29 "B.CrtYd" user "Package Geometry/Place Bound Bottom")
		(35 "F.Fab" user "Ref Des/Assembly Top")
		(33 "B.Fab" user "Ref Des/Assembly Bottom")
	)
	(footprint ""
		(layer "F.Cu")
		(at 29.699458 -133.0706 90)
		(property "Reference" "J1B1"
			(at -4.960112 38.372542 0)
			(unlocked yes)
			(layer "F.SilkS")
			(effects
				(font
					(size 0.7874 0.5842)
					(thickness 0.1524)
				)
				(justify left)
			)
		)
		(property "Value" ""
			(at 0 0 90)
			(layer "F.Fab")
			(effects
				(font
					(size 1.27 1.27)
				)
			)
		)
		(duplicate_pad_numbers_are_jumpers no)
		(pad "150" smd rect
			(at 4.59994 4.249928 90)
			(size 1.8034 0.508)
			(layers "F.Cu" "F.Mask" "F.Paste")
			(net "M_K_DQ<0>")
		)
		(pad "151" smd rect
			(at 4.59994 5.100066 90)
			(size 1.8034 0.508)
			(layers "F.Cu" "F.Mask" "F.Paste")
			(net "GND")
		)
		(pad "152" smd rect
			(at 4.59994 5.94995 90)
			(size 1.8034 0.508)
			(layers "F.Cu" "F.Mask" "F.Paste")
			(net "M_K_DQS_DN<0>")
		)
		(pad "153" smd rect
			(at 4.59994 6.800088 90)
			(size 1.8034 0.508)
			(layers "F.Cu" "F.Mask" "F.Paste")
			(net "M_K_DQS_DP<0>")
		)
		(pad "154" smd rect
			(at 4.59994 7.649972 90)
			(size 1.8034 0.508)
			(layers "F.Cu" "F.Mask" "F.Paste")
			(net "GND")
		)
		(pad "155" smd rect
			(at 4.59994 8.50011 90)
			(size 1.8034 0.508)
			(layers "F.Cu" "F.Mask" "F.Paste")
			(net "M_K_DQ<6>")
		)
		(pad "156" smd rect
			(at 4.59994 9.349994 90)
			(size 1.8034 0.508)
			(layers "F.Cu" "F.Mask" "F.Paste")
			(net "GND")
		)
		(pad "157" smd rect
			(at 4.59994 10.199878 90)
			(size 1.8034 0.508)
			(layers "F.Cu" "F.Mask" "F.Paste")
			(net "M_K_DQ<2>")
		)
		(pad "158" smd rect
			(at 4.59994 11.050016 90)
			(size 1.8034 0.508)
			(layers "F.Cu" "F.Mask" "F.Paste")
			(net "GND")
		)
		(pad "159" smd rect
			(at 4.59994 11.8999 90)
			(size 1.8034 0.508)
			(layers "F.Cu" "F.Mask" "F.Paste")
			(net "M_K_DQ<12>")
		)
		(pad "160" smd rect
			(at 4.59994 12.750038 90)
			(size 1.8034 0.508)
			(layers "F.Cu" "F.Mask" "F.Paste")
			(net "GND")
		)
		(pad "161" smd rect
			(at 4.59994 13.599922 90)
			(size 1.8034 0.508)
			(layers "F.Cu" "F.Mask" "F.Paste")
			(net "M_K_DQ<8>")
		)
		(pad "162" smd rect
			(at 4.59994 14.45006 90)
			(size 1.8034 0.508)
			(layers "F.Cu" "F.Mask" "F.Paste")
			(net "GND")
		)
		(pad "163" smd rect
			(at 4.59994 15.299944 90)
			(size 1.8034 0.508)
			(layers "F.Cu" "F.Mask" "F.Paste")
			(net "M_K_DQS_DN<1>")
		)
		(pad "164" smd rect
			(at 4.59994 16.150082 90)
			(size 1.8034 0.508)
			(layers "F.Cu" "F.Mask" "F.Paste")
			(net "M_K_DQS_DP<1>")
		)
		(pad "165" smd rect
			(at 4.59994 16.999966 90)
			(size 1.8034 0.508)
			(layers "F.Cu" "F.Mask" "F.Paste")
			(net "GND")
		)
		(pad "166" smd rect
			(at 4.59994 17.850104 90)
			(size 1.8034 0.508)
			(layers "F.Cu" "F.Mask" "F.Paste")
			(net "M_K_DQ<14>")
		)
		(pad "167" smd rect
			(at 4.59994 18.699988 90)
			(size 1.8034 0.508)
			(layers "F.Cu" "F.Mask" "F.Paste")
			(net "GND")
		)
		(pad "168" smd rect
			(at 4.59994 19.550126 90)
			(size 1.8034 0.508)
			(layers "F.Cu" "F.Mask" "F.Paste")
			(net "M_K_DQ<10>")
		)
		(pad "169" smd rect
			(at 4.59994 20.40001 90)
			(size 1.8034 0.508)
			(layers "F.Cu" "F.Mask" "F.Paste")
			(net "GND")
		)
		(pad "170" smd rect
			(at 4.59994 21.249894 90)
			(size 1.8034 0.508)
			(layers "F.Cu" "F.Mask" "F.Paste")
			(net "M_K_DQ<20>")
		)
		(pad "171" smd rect
			(at 4.59994 22.100032 90)
			(size 1.8034 0.508)
			(layers "F.Cu" "F.Mask" "F.Paste")
			(net "GND")
		)
		(pad "172" smd rect
			(at 4.59994 22.949916 90)
			(size 1.8034 0.508)
			(layers "F.Cu" "F.Mask" "F.Paste")
			(net "M_K_DQ<16>")
		)
		(pad "173" smd rect
			(at 4.59994 23.800054 90)
			(size 1.8034 0.508)
			(layers "F.Cu" "F.Mask" "F.Paste")
			(net "GND")
		)
		(pad "174" smd rect
			(at 4.59994 24.649938 90)
			(size 1.8034 0.508)
			(layers "F.Cu" "F.Mask" "F.Paste")
			(net "M_K_DQS_DN<2>")
		)
		(pad "175" smd rect
			(at 4.59994 25.500076 90)
			(size 1.8034 0.508)
			(layers "F.Cu" "F.Mask" "F.Paste")
			(net "M_K_DQS_DP<2>")
		)
		(pad "176" smd rect
			(at 4.59994 26.34996 90)
			(size 1.8034 0.508)
			(layers "F.Cu" "F.Mask" "F.Paste")
			(net "GND")
		)
		(pad "177" smd rect
			(at 4.59994 27.200098 90)
			(size 1.8034 0.508)
			(layers "F.Cu" "F.Mask" "F.Paste")
			(net "M_K_DQ<22>")
		)
		(pad "178" smd rect
			(at 4.59994 28.049982 90)
			(size 1.8034 0.508)
			(layers "F.Cu" "F.Mask" "F.Paste")
			(net "GND")
		)
		(pad "179" smd rect
			(at 4.59994 28.90012 90)
			(size 1.8034 0.508)
			(layers "F.Cu" "F.Mask" "F.Paste")
			(net "M_K_DQ<18>")
		)
		(pad "180" smd rect
			(at 4.59994 29.750004 90)
			(size 1.8034 0.508)
			(layers "F.Cu" "F.Mask" "F.Paste")
			(net "GND")
		)
		(pad "181" smd rect
			(at 4.59994 30.599888 90)
			(size 1.8034 0.508)
			(layers "F.Cu" "F.Mask" "F.Paste")
			(net "M_K_DQ<28>")
		)
		(pad "182" smd rect
			(at 4.59994 31.450026 90)
			(size 1.8034 0.508)
			(layers "F.Cu" "F.Mask" "F.Paste")
			(net "GND")
		)
		(pad "183" smd rect
			(at 4.59994 32.29991 90)
			(size 1.8034 0.508)
			(layers "F.Cu" "F.Mask" "F.Paste")
			(net "M_K_DQ<24>")
		)
		(pad "184" smd rect
			(at 4.59994 33.150048 90)
			(size 1.8034 0.508)
			(layers "F.Cu" "F.Mask" "F.Paste")
			(net "GND")
		)
		(pad "185" smd rect
			(at 4.59994 33.999932 90)
			(size 1.8034 0.508)
			(layers "F.Cu" "F.Mask" "F.Paste")
			(net "M_K_DQS_DN<3>")
		)
		(pad "186" smd rect
			(at 4.59994 34.85007 90)
			(size 1.8034 0.508)
			(layers "F.Cu" "F.Mask" "F.Paste")
			(net "M_K_DQS_DP<3>")
		)
		(pad "187" smd rect
			(at 4.59994 35.699954 90)
			(size 1.8034 0.508)
			(layers "F.Cu" "F.Mask" "F.Paste")
			(net "GND")
		)
		(pad "188" smd rect
			(at 4.59994 36.550092 90)
			(size 1.8034 0.508)
			(layers "F.Cu" "F.Mask" "F.Paste")
			(net "M_K_DQ<30>")
		)
		(pad "189" smd rect
			(at 4.59994 37.399976 90)
			(size 1.8034 0.508)
			(layers "F.Cu" "F.Mask" "F.Paste")
			(net "GND")
		)
		(pad "190" smd rect
			(at 4.59994 38.250114 90)
			(size 1.8034 0.508)
			(layers "F.Cu" "F.Mask" "F.Paste")
			(net "M_K_DQ<26>")
		)
		(pad "191" smd rect
			(at 4.59994 39.099998 90)
			(size 1.8034 0.508)
			(layers "F.Cu" "F.Mask" "F.Paste")
			(net "GND")
		)
		(pad "192" smd rect
			(at 4.59994 39.949882 90)
			(size 1.8034 0.508)
			(layers "F.Cu" "F.Mask" "F.Paste")
			(net "M_K_ECC<4>")
		)
		(pad "193" smd rect
			(at 4.59994 40.80002 90)
			(size 1.8034 0.508)
			(layers "F.Cu" "F.Mask" "F.Paste")
			(net "GND")
		)
		(pad "194" smd rect
			(at 4.59994 41.649904 90)
			(size 1.8034 0.508)
			(layers "F.Cu" "F.Mask" "F.Paste")
			(net "M_K_ECC<0>")
		)
		(pad "195" smd rect
			(at 4.59994 42.500042 90)
			(size 1.8034 0.508)
			(layers "F.Cu" "F.Mask" "F.Paste")
			(net "GND")
		)
		(pad "196" smd rect
			(at 4.59994 43.349926 90)
			(size 1.8034 0.508)
			(layers "F.Cu" "F.Mask" "F.Paste")
			(net "M_K_DQS_DN<8>")
		)
		(pad "197" smd rect
			(at 4.59994 44.200064 90)
			(size 1.8034 0.508)
			(layers "F.Cu" "F.Mask" "F.Paste")
			(net "M_K_DQS_DP<8>")
		)
		(pad "198" smd rect
			(at 4.59994 45.049948 90)
			(size 1.8034 0.508)
			(layers "F.Cu" "F.Mask" "F.Paste")
			(net "GND")
		)
		(pad "199" smd rect
			(at 4.59994 45.900086 90)
			(size 1.8034 0.508)
			(layers "F.Cu" "F.Mask" "F.Paste")
			(net "M_K_ECC<6>")
		)
	)
)
